# TIMECARD (Time Appliance Project (Time Card)) — schematic netlist excerpt (pin names and nets, part order shuffled) for the footprints in the layout excerpt that follows; sources: Cadence DE-HDL packaged netlist, KiCad conversion of R4006-B0001-02_R01.brd

R214  RESISTOR  1KOHM 1%  pkg SMC_0402R_H016  page 10 : \1\ = FPGA_BRD_REV2 ; \2\ = SG
R184  RESISTOR  33OHM 1%  pkg SMC_0402R_H016  page 16 : \1\ = EEPROM_I2C_SCL ; \2\ = EEPROM_SCL

(kicad_pcb
	(version 20260206)
	(generator "pcbnew")
	(generator_version "10.0")
	(general
		(thickness 1.6)
		(legacy_teardrops no)
	)
	(paper "A4")
	(title_block
		(title "timecard-production-celestica-r4006 — R4006-B0001-02_R01.brd")
		(comment 1 "Time Appliance Project (Time Card) / footprints 617-618 of 1113")
	)
	(layers
		(0 "F.Cu" signal "TOP")
		(4 "In1.Cu" signal "L02_GND1")
		(6 "In2.Cu" signal "L03_SIG1")
		(8 "In3.Cu" signal "L04_GND2")
		(10 "In4.Cu" signal "L05_VCC1")
		(12 "In5.Cu" signal "L06_VCC2")
		(14 "In6.Cu" signal "L07_GND3")
		(16 "In7.Cu" signal "L08_SIG2")
		(18 "In8.Cu" signal "L09_GND4")
		(2 "B.Cu" signal "BOTTOM")
		(9 "F.Adhes" user "F.Adhesive")
		(11 "B.Adhes" user "B.Adhesive")
		(13 "F.Paste" user "Package Geometry/Pastemask Top")
		(15 "B.Paste" user "Package Geometry/Pastemask Bottom")
		(5 "F.SilkS" user "Ref Des/Silkscreen Top")
		(7 "B.SilkS" user "Ref Des/Silkscreen Bottom")
		(1 "F.Mask" user "Board Geometry/Soldermask Top")
		(3 "B.Mask" user "Board Geometry/Soldermask Bottom")
		(17 "Dwgs.User" user "User.Drawings")
		(19 "Cmts.User" user "User.Comments")
		(21 "Eco1.User" user "User.Eco1")
		(23 "Eco2.User" user "User.Eco2")
		(25 "Edge.Cuts" user "Board Geometry/Outline")
		(27 "Margin" user)
		(31 "F.CrtYd" user "Package Geometry/Place Bound Top")
		(29 "B.CrtYd" user "Package Geometry/Place Bound Bottom")
		(35 "F.Fab" user "Ref Des/Assembly Top")
		(33 "B.Fab" user "Ref Des/Assembly Bottom")
	)
	(footprint ""
		(layer "F.Cu")
		(at 112.776 -61.976 90)
		(property "Reference" "R214"
			(at 3.302 0.42037 90)
			(unlocked yes)
			(layer "F.SilkS")
			(effects
				(font
					(size 0.7874 0.5842)
					(thickness 0.1524)
				)
			)
		)
		(property "Value" "VAL*"
			(at 0.02032 2.13233 90)
			(unlocked yes)
			(layer "F.Fab")
			(hide yes)
			(effects
				(font
					(size 0.7874 0.5842)
					(thickness 0.1524)
				)
			)
		)
		(property "Device Type" "RESISTOR-G155-11001-01,1KOHM,1%"
			(at 0.008382 1.210564 90)
			(unlocked yes)
			(layer "F.Fab")
			(hide yes)
			(effects
				(font
					(size 0.7874 0.5842)
					(thickness 0.1524)
				)
			)
		)
		(property "User Part Number" "PARTNUM*"
			(at 0.02032 4.024884 90)
			(unlocked yes)
			(layer "Cmts.User")
			(hide yes)
			(effects
				(font
					(size 0.7874 0.5842)
					(thickness 0.1524)
				)
			)
		)
		(property "Tolerance" "TOL*"
			(at 0.044704 3.05435 90)
			(unlocked yes)
			(layer "Cmts.User")
			(hide yes)
			(effects
				(font
					(size 0.7874 0.5842)
					(thickness 0.1524)
				)
			)
		)
		(duplicate_pad_numbers_are_jumpers no)
		(fp_line
			(start 1.143 -0.5588)
			(end -1.143 -0.5588)
			(stroke
				(width 0.1)
				(type default)
			)
			(layer "F.SilkS")
		)
		(fp_line
			(start -1.143 -0.5588)
			(end -1.143 0.5588)
			(stroke
				(width 0.1)
				(type default)
			)
			(layer "F.SilkS")
		)
		(fp_line
			(start 1.143 0.5588)
			(end 1.143 -0.5588)
			(stroke
				(width 0.1)
				(type default)
			)
			(layer "F.SilkS")
		)
		(fp_line
			(start -1.143 0.5588)
			(end 1.143 0.5588)
			(stroke
				(width 0.1)
				(type default)
			)
			(layer "F.SilkS")
		)
		(fp_rect
			(start -1.143 0.5588)
			(end 1.143 -0.5588)
			(stroke
				(width 0)
				(type default)
			)
			(fill no)
			(layer "F.CrtYd")
		)
		(fp_line
			(start 0.508 -0.3048)
			(end -0.508 -0.3048)
			(stroke
				(width 0.1)
				(type default)
			)
			(layer "F.Fab")
		)
		(fp_line
			(start -0.508 -0.3048)
			(end -0.508 0.3048)
			(stroke
				(width 0.1)
				(type default)
			)
			(layer "F.Fab")
		)
		(fp_line
			(start 0.508 0.3048)
			(end 0.508 -0.3048)
			(stroke
				(width 0.1)
				(type default)
			)
			(layer "F.Fab")
		)
		(fp_line
			(start -0.508 0.3048)
			(end 0.508 0.3048)
			(stroke
				(width 0.1)
				(type default)
			)
			(layer "F.Fab")
		)
		(pad "1" smd rect
			(at -0.5334 0 90)
			(size 0.7112 0.6096)
			(layers "F.Cu" "F.Mask" "F.Paste")
			(net "FPGA_BRD_REV2")
		)
		(pad "2" smd rect
			(at 0.5334 0 90)
			(size 0.7112 0.6096)
			(layers "F.Cu" "F.Mask" "F.Paste")
			(net "SG")
		)
		(zone
			(layer "F.Cu")
			(hatch none 0.5)
			(connect_pads
				(clearance 0)
			)
			(min_thickness 0.25)
			(keepout
				(tracks allowed)
				(vias not_allowed)
				(pads allowed)
				(copperpour not_allowed)
				(footprints allowed)
			)
			(placement
				(enabled no)
				(sheetname "")
			)
			(fill
				(thermal_gap 0.5)
				(thermal_bridge_width 0.5)
				(island_removal_mode 0)
			)
			(polygon
				(pts
					(xy 113.0808 -61.8998) (xy 113.0808 -62.0522) (xy 112.4712 -62.0522) (xy 112.4712 -61.8998)
				)
			)
		)
	)
	(footprint ""
		(layer "F.Cu")
		(at 33.77438 -17.9832 180)
		(property "Reference" "R184"
			(at -2.80162 -1.38557 0)
			(unlocked yes)
			(layer "F.SilkS")
			(effects
				(font
					(size 0.7874 0.5842)
					(thickness 0.1524)
				)
			)
		)
		(property "Value" "VAL*"
			(at 0.02032 2.13233 180)
			(unlocked yes)
			(layer "F.Fab")
			(hide yes)
			(effects
				(font
					(size 0.7874 0.5842)
					(thickness 0.1524)
				)
			)
		)
		(property "Tolerance" "TOL*"
			(at 0.044704 3.05435 180)
			(unlocked yes)
			(layer "Cmts.User")
			(hide yes)
			(effects
				(font
					(size 0.7874 0.5842)
					(thickness 0.1524)
				)
			)
		)
		(property "User Part Number" "PARTNUM*"
			(at 0.02032 4.024884 180)
			(unlocked yes)
			(layer "Cmts.User")
			(hide yes)
			(effects
				(font
					(size 0.7874 0.5842)
					(thickness 0.1524)
				)
			)
		)
		(property "Device Type" "RESISTOR-G155-133R0-01,33OHM,1%"
			(at 0.008382 1.210564 180)
			(unlocked yes)
			(layer "F.Fab")
			(hide yes)
			(effects
				(font
					(size 0.7874 0.5842)
					(thickness 0.1524)
				)
			)
		)
		(duplicate_pad_numbers_are_jumpers no)
		(fp_line
			(start 1.143 0.5588)
			(end 1.143 -0.5588)
			(stroke
				(width 0.1)
				(type default)
			)
			(layer "F.SilkS")
		)
		(fp_line
			(start 1.143 -0.5588)
			(end -1.143 -0.5588)
			(stroke
				(width 0.1)
				(type default)
			)
			(layer "F.SilkS")
		)
		(fp_line
			(start -1.143 0.5588)
			(end 1.143 0.5588)
			(stroke
				(width 0.1)
				(type default)
			)
			(layer "F.SilkS")
		)
		(fp_line
			(start -1.143 -0.5588)
			(end -1.143 0.5588)
			(stroke
				(width 0.1)
				(type default)
			)
			(layer "F.SilkS")
		)
		(fp_rect
			(start 1.143 -0.5588)
			(end -1.143 0.5588)
			(stroke
				(width 0)
				(type default)
			)
			(fill no)
			(layer "F.CrtYd")
		)
		(fp_line
			(start 0.508 0.3048)
			(end 0.508 -0.3048)
			(stroke
				(width 0.1)
				(type default)
			)
			(layer "F.Fab")
		)
		(fp_line
			(start 0.508 -0.3048)
			(end -0.508 -0.3048)
			(stroke
				(width 0.1)
				(type default)
			)
			(layer "F.Fab")
		)
		(fp_line
			(start -0.508 0.3048)
			(end 0.508 0.3048)
			(stroke
				(width 0.1)
				(type default)
			)
			(layer "F.Fab")
		)
		(fp_line
			(start -0.508 -0.3048)
			(end -0.508 0.3048)
			(stroke
				(width 0.1)
				(type default)
			)
			(layer "F.Fab")
		)
		(pad "1" smd rect
			(at -0.5334 0 180)
			(size 0.7112 0.6096)
			(layers "F.Cu" "F.Mask" "F.Paste")
			(net "EEPROM_I2C_SCL")
		)
		(pad "2" smd rect
			(at 0.5334 0 180)
			(size 0.7112 0.6096)
			(layers "F.Cu" "F.Mask" "F.Paste")
			(net "EEPROM_SCL")
		)
		(zone
			(layer "F.Cu")
			(hatch none 0.5)
			(connect_pads
				(clearance 0)
			)
			(min_thickness 0.25)
			(keepout
				(tracks allowed)
				(vias not_allowed)
				(pads allowed)
				(copperpour not_allowed)
				(footprints allowed)
			)
			(placement
				(enabled no)
				(sheetname "")
			)
			(fill
				(thermal_gap 0.5)
				(thermal_bridge_width 0.5)
				(island_removal_mode 0)
			)
			(polygon
				(pts
					(xy 33.69818 -17.6784) (xy 33.85058 -17.6784) (xy 33.85058 -18.288) (xy 33.69818 -18.288)
				)
			)
		)
	)
)
